# BASEBOARD_FAB2 (Tioga Pass) — schematic netlist excerpt (pin names and nets, part order shuffled) for the footprints in the layout excerpt that follows; sources: Cadence DE-HDL packaged netlist, KiCad conversion of Wiwynn_Tioga_Pass_MB.brd

J6L1  SCONN288_H44441003  SCONN  pkg PIP  page 54
  \12v\(1)  = P12V_NVDIMM_DEF
  VSS(93)  = GND
  DQ(4)  = M_F_DQ<4>
  VSS(92)  = GND
  DQ(0)  = M_F_DQ<0>
  VSS(91)  = GND
  DQS9P  = M_F_DQS_DP<9>
  DQS9N  = M_F_DQS_DN<9>
  VSS(90)  = GND
  DQ(6)  = M_F_DQ<6>
  VSS(89)  = GND
  DQ(2)  = M_F_DQ<2>
  VSS(88)  = GND
  DQ(12)  = M_F_DQ<12>
  VSS(87)  = GND
  DQ(8)  = M_F_DQ<8>
  VSS(86)  = GND
  DQS10P  = M_F_DQS_DP<10>
  DQS10N  = M_F_DQS_DN<10>
  VSS(85)  = GND
  DQ(14)  = M_F_DQ<14>
  VSS(84)  = GND
  DQ(10)  = M_F_DQ<10>
  VSS(83)  = GND
  DQ(20)  = M_F_DQ<20>
  VSS(82)  = GND
  DQ(16)  = M_F_DQ<16>
  VSS(81)  = GND
  DQS11P  = M_F_DQS_DP<11>
  DQS11N  = M_F_DQS_DN<11>
  VSS(80)  = GND
  DQ(22)  = M_F_DQ<22>
  VSS(79)  = GND
  DQ(18)  = M_F_DQ<18>
  VSS(78)  = GND
  DQ(28)  = M_F_DQ<28>
  VSS(77)  = GND
  DQ(24)  = M_F_DQ<24>
  VSS(76)  = GND
  DQS12P  = M_F_DQS_DP<12>
  DQS12N  = M_F_DQS_DN<12>
  VSS(75)  = GND
  DQ(30)  = M_F_DQ<30>
  VSS(74)  = GND
  DQ(26)  = M_F_DQ<26>
  VSS(73)  = GND
  CB(4)  = M_F_ECC<4>
  VSS(72)  = GND
  CB(0)  = M_F_ECC<0>
  VSS(71)  = GND
  DQS17P  = M_F_DQS_DP<17>
  DQS17N  = M_F_DQS_DN<17>
  VSS(70)  = GND
  CB(6)  = M_F_ECC<6>
  VSS(69)  = GND
  CB(2)  = M_F_ECC<2>
  VSS(68)  = GND
  RESET_N  = M_DEF_RST_N
  VDD(25)  = PVDDQ_DEF
  CKE(0)  = M_F_CKE<2>
  VDD(24)  = PVDDQ_DEF
  ACT_N  = M_F_ACT_N
  BG(0)  = M_F_BG<0>
  VDD(23)  = PVDDQ_DEF
  A12  = M_F_MA<12>
  A9  = M_F_MA<9>
  VDD(22)  = PVDDQ_DEF
  A8  = M_F_MA<8>
  A6  = M_F_MA<6>
  VDD(21)  = PVDDQ_DEF
  A3  = M_F_MA<3>
  A1  = M_F_MA<1>
  VDD(20)  = PVDDQ_DEF
  CK0P  = M_F_CLK_DP<2>
  CK0N  = M_F_CLK_DN<2>
  VDD(19)  = PVDDQ_DEF
  VTT(1)  = PVTT_DEF
  EVENT_N  = FM_DIMM_EVENT_COD_N
  A0  = M_F_MA<0>
  VDD(18)  = PVDDQ_DEF
  BA(0)  = M_F_BA<0>
  A16_RAS_N  = M_F_MA<16>
  VDD(17)  = PVDDQ_DEF
  S0_N  = M_F_CS_N<4>
  VDD(16)  = PVDDQ_DEF
  A15_CAS_N  = M_F_MA<15>
  ODT(0)  = M_F_ODT<2>
  VDD(15)  = PVDDQ_DEF
  S1_N  = M_F_CS_N<5>
  VDD(14)  = PVDDQ_DEF
  ODT(1)  = M_F_ODT<3>
  VDD(13)  = PVDDQ_DEF
  S2_N_C(0)  = M_F_CS_N<6>
  VSS(67)  = GND
  DQ(36)  = M_F_DQ<36>
  VSS(66)  = GND
  DQ(32)  = M_F_DQ<32>
  VSS(65)  = GND
  DQS13P  = M_F_DQS_DP<13>
  DQS13N  = M_F_DQS_DN<13>
  VSS(64)  = GND
  DQ(38)  = M_F_DQ<38>
  VSS(63)  = GND
  DQ(34)  = M_F_DQ<34>
  VSS(62)  = GND
  DQ(44)  = M_F_DQ<44>
  VSS(61)  = GND
  DQ(40)  = M_F_DQ<40>
  VSS(60)  = GND
  DQS14P  = M_F_DQS_DP<14>
  DQS14N  = M_F_DQS_DN<14>
  VSS(59)  = GND
  DQ(46)  = M_F_DQ<46>
  VSS(58)  = GND
  DQ(42)  = M_F_DQ<42>
  VSS(57)  = GND
  DQ(52)  = M_F_DQ<52>
  VSS(56)  = GND
  DQ(48)  = M_F_DQ<48>
  VSS(55)  = GND
  DQS15P  = M_F_DQS_DP<15>
  DQS15N  = M_F_DQS_DN<15>
  VSS(54)  = GND
  DQ(54)  = M_F_DQ<54>
  VSS(53)  = GND
  DQ(50)  = M_F_DQ<50>
  VSS(52)  = GND
  DQ(60)  = M_F_DQ<60>
  VSS(51)  = GND
  DQ(56)  = M_F_DQ<56>
  VSS(50)  = GND
  DQS16P  = M_F_DQS_DP<16>
  DQS16N  = M_F_DQS_DN<16>
  VSS(49)  = GND
  DQ(62)  = M_F_DQ<62>
  VSS(48)  = GND
  DQ(58)  = M_F_DQ<58>
  VSS(47)  = GND
  SA(0)  = PVPP_DEF
  SA(1)  = GND
  SCL  = SMB_DDR_DEF_VPP_SCL
  VPP(4)  = PVPP_DEF
  VPP(3)  = PVPP_DEF
  RFU(2)  = TP_CH_F_DIMM_F1_RFU_2
  \12v\(0)  = P12V_NVDIMM_DEF
  VREFCA  = M_F_VREF
  VSS(46)  = GND
  DQ(5)  = M_F_DQ<5>
  VSS(45)  = GND
  DQ(1)  = M_F_DQ<1>
  VSS(44)  = GND
  DQS0N  = M_F_DQS_DN<0>
  DQS0P  = M_F_DQS_DP<0>
  VSS(43)  = GND
  DQ(7)  = M_F_DQ<7>
  VSS(42)  = GND
  DQ(3)  = M_F_DQ<3>
  VSS(41)  = GND
  DQ(13)  = M_F_DQ<13>
  VSS(40)  = GND
  DQ(9)  = M_F_DQ<9>
  VSS(39)  = GND
  DQS1N  = M_F_DQS_DN<1>
  DQS1P  = M_F_DQS_DP<1>
  VSS(38)  = GND
  DQ(15)  = M_F_DQ<15>
  VSS(37)  = GND
  DQ(11)  = M_F_DQ<11>
  VSS(36)  = GND
  DQ(21)  = M_F_DQ<21>
  VSS(35)  = GND
  DQ(17)  = M_F_DQ<17>
  VSS(34)  = GND
  DQS2N  = M_F_DQS_DN<2>
  DQS2P  = M_F_DQS_DP<2>
  VSS(33)  = GND
  DQ(23)  = M_F_DQ<23>
  VSS(32)  = GND
  DQ(19)  = M_F_DQ<19>
  VSS(31)  = GND
  DQ(29)  = M_F_DQ<29>
  VSS(30)  = GND
  DQ(25)  = M_F_DQ<25>
  VSS(29)  = GND
  DQS3N  = M_F_DQS_DN<3>
  DQS3P  = M_F_DQS_DP<3>
  VSS(28)  = GND
  DQ(31)  = M_F_DQ<31>
  VSS(27)  = GND
  DQ(27)  = M_F_DQ<27>
  VSS(26)  = GND
  CB(5)  = M_F_ECC<5>
  VSS(25)  = GND
  CB(1)  = M_F_ECC<1>
  VSS(24)  = GND
  DQS8N  = M_F_DQS_DN<8>
  DQS8P  = M_F_DQS_DP<8>
  VSS(23)  = GND
  CB(7)  = M_F_ECC<7>
  VSS(22)  = GND
  CB(3)  = M_F_ECC<3>
  VSS(21)  = GND
  CKE(1)  = M_F_CKE<3>
  VDD(12)  = PVDDQ_DEF
  RFU(0)  = TP_CH_F_DIMM_F1_RFU_0
  VDD(11)  = PVDDQ_DEF
  BG(1)  = M_F_BG<1>
  ALERT_N  = M_F_ALERT_N
  VDD(10)  = PVDDQ_DEF
  A11  = M_F_MA<11>
  A7  = M_F_MA<7>
  VDD(9)  = PVDDQ_DEF
  A5  = M_F_MA<5>
  A4  = M_F_MA<4>
  VDD(8)  = PVDDQ_DEF
  A2  = M_F_MA<2>
  VDD(7)  = PVDDQ_DEF
  CK1P  = M_F_CLK_DP<3>
  CK1N  = M_F_CLK_DN<3>
  VDD(6)  = PVDDQ_DEF
  VTT(0)  = PVTT_DEF
  PAR  = M_F_PAR
  VDD(5)  = PVDDQ_DEF
  BA(1)  = M_F_BA<1>
  A10  = M_F_MA<10>
  VDD(4)  = PVDDQ_DEF
  RFU(1)  = TP_CH_F_DIMM_F1_RFU_1
  A14_WE_N  = M_F_MA<14>
  VDD(3)  = PVDDQ_DEF
  SAVE_N_NC  = FM_ADR_COMPLETE_DEF_N
  VDD(2)  = PVDDQ_DEF
  A13  = M_F_MA<13>
  VDD(1)  = PVDDQ_DEF
  A17  = M_F_MA<17>
  C(2)  = M_F_C<2>
  VDD(0)  = PVDDQ_DEF
  S3_N_C(1)  = M_F_CS_N<7>
  SA(2)  = PVPP_DEF
  VSS(20)  = GND
  DQ(37)  = M_F_DQ<37>
  VSS(19)  = GND
  DQ(33)  = M_F_DQ<33>
  VSS(18)  = GND
  DQS4N  = M_F_DQS_DN<4>
  DQS4P  = M_F_DQS_DP<4>
  VSS(17)  = GND
  DQ(39)  = M_F_DQ<39>
  VSS(16)  = GND
  DQ(35)  = M_F_DQ<35>
  VSS(15)  = GND
  DQ(45)  = M_F_DQ<45>
  VSS(14)  = GND
  DQ(41)  = M_F_DQ<41>
  VSS(13)  = GND
  DQS5N  = M_F_DQS_DN<5>
  DQS5P  = M_F_DQS_DP<5>
  VSS(12)  = GND
  DQ(47)  = M_F_DQ<47>
  VSS(11)  = GND
  DQ(43)  = M_F_DQ<43>
  VSS(10)  = GND
  DQ(53)  = M_F_DQ<53>
  VSS(9)  = GND
  DQ(49)  = M_F_DQ<49>
  VSS(8)  = GND
  DQS6N  = M_F_DQS_DN<6>
  DQS6P  = M_F_DQS_DP<6>
  VSS(7)  = GND
  DQ(55)  = M_F_DQ<55>
  VSS(6)  = GND
  DQ(51)  = M_F_DQ<51>
  VSS(5)  = GND
  DQ(61)  = M_F_DQ<61>
  VSS(4)  = GND
  DQ(57)  = M_F_DQ<57>
  VSS(3)  = GND
  DQS7N  = M_F_DQS_DN<7>
  DQS7P  = M_F_DQS_DP<7>
  VSS(2)  = GND
  DQ(63)  = M_F_DQ<63>
  VSS(1)  = GND
  DQ(59)  = M_F_DQ<59>
  VSS(0)  = GND
  VDDSPD  = PVPP_DEF
  SDA  = SMB_DDR_DEF_VPP_SDA
  VPP(1)  = PVPP_DEF
  VPP(0)  = PVPP_DEF
  VPP(2)  = PVPP_DEF

(kicad_pcb
	(version 20260206)
	(generator "pcbnew")
	(generator_version "10.0")
	(general
		(thickness 1.6)
		(legacy_teardrops no)
	)
	(paper "A4")
	(title_block
		(title "Wiwynn_Tioga_Pass_MB.brd")
		(comment 1 "Tioga Pass / footprint 4129 of 4770 (J6L1), pads 250-291 of 291")
	)
	(layers
		(0 "F.Cu" signal "TOP")
		(4 "In1.Cu" signal "L2GND")
		(6 "In2.Cu" signal "L3")
		(8 "In3.Cu" signal "L4GND")
		(10 "In4.Cu" signal "L5")
		(12 "In5.Cu" signal "L6GND")
		(14 "In6.Cu" signal "L7VCC")
		(16 "In7.Cu" signal "L8VCC")
		(18 "In8.Cu" signal "L9GND")
		(20 "In9.Cu" signal "L10")
		(22 "In10.Cu" signal "L11GND")
		(24 "In11.Cu" signal "L12")
		(26 "In12.Cu" signal "L13GND")
		(2 "B.Cu" signal "BOTTOM")
		(9 "F.Adhes" user "F.Adhesive")
		(11 "B.Adhes" user "B.Adhesive")
		(13 "F.Paste" user "Package Geometry/Pastemask Top")
		(15 "B.Paste" user "Package Geometry/Pastemask Bottom")
		(5 "F.SilkS" user "Ref Des/Silkscreen Top")
		(7 "B.SilkS" user "Ref Des/Silkscreen Bottom")
		(1 "F.Mask" user "Board Geometry/Soldermask Top")
		(3 "B.Mask" user "Board Geometry/Soldermask Bottom")
		(17 "Dwgs.User" user "User.Drawings")
		(19 "Cmts.User" user "User.Comments")
		(21 "Eco1.User" user "User.Eco1")
		(23 "Eco2.User" user "User.Eco2")
		(25 "Edge.Cuts" user "Board Geometry/Outline")
		(27 "Margin" user)
		(31 "F.CrtYd" user "Package Geometry/Place Bound Top")
		(29 "B.CrtYd" user "Package Geometry/Place Bound Bottom")
		(35 "F.Fab" user "Ref Des/Assembly Top")
		(33 "B.Fab" user "Ref Des/Assembly Bottom")
	)
	(footprint ""
		(layer "B.Cu")
		(at 194.700398 -152.078436 90)
		(property "Reference" "J6L1"
			(at 2.200148 37.96411 0)
			(unlocked yes)
			(layer "B.SilkS")
			(effects
				(font
					(size 0.7874 0.5842)
					(thickness 0.1524)
				)
				(justify left mirror)
			)
		)
		(property "Value" ""
			(at 0 0 90)
			(layer "B.Fab")
			(effects
				(font
					(size 1.27 1.27)
				)
				(justify mirror)
			)
		)
		(duplicate_pad_numbers_are_jumpers no)
		(pad "247" smd rect
			(at -4.59994 91.799918 270)
			(size 1.8034 0.508)
			(layers "B.Cu" "B.Mask" "B.Paste")
			(net "M_F_DQ<39>")
		)
		(pad "248" smd rect
			(at -4.59994 92.650056 270)
			(size 1.8034 0.508)
			(layers "B.Cu" "B.Mask" "B.Paste")
			(net "GND")
		)
		(pad "249" smd rect
			(at -4.59994 93.49994 270)
			(size 1.8034 0.508)
			(layers "B.Cu" "B.Mask" "B.Paste")
			(net "M_F_DQ<35>")
		)
		(pad "250" smd rect
			(at -4.59994 94.350078 270)
			(size 1.8034 0.508)
			(layers "B.Cu" "B.Mask" "B.Paste")
			(net "GND")
		)
		(pad "251" smd rect
			(at -4.59994 95.199962 270)
			(size 1.8034 0.508)
			(layers "B.Cu" "B.Mask" "B.Paste")
			(net "M_F_DQ<45>")
		)
		(pad "252" smd rect
			(at -4.59994 96.0501 270)
			(size 1.8034 0.508)
			(layers "B.Cu" "B.Mask" "B.Paste")
			(net "GND")
		)
		(pad "253" smd rect
			(at -4.59994 96.899984 270)
			(size 1.8034 0.508)
			(layers "B.Cu" "B.Mask" "B.Paste")
			(net "M_F_DQ<41>")
		)
		(pad "254" smd rect
			(at -4.59994 97.750122 270)
			(size 1.8034 0.508)
			(layers "B.Cu" "B.Mask" "B.Paste")
			(net "GND")
		)
		(pad "255" smd rect
			(at -4.59994 98.600006 270)
			(size 1.8034 0.508)
			(layers "B.Cu" "B.Mask" "B.Paste")
			(net "M_F_DQS_DN<5>")
		)
		(pad "256" smd rect
			(at -4.59994 99.44989 270)
			(size 1.8034 0.508)
			(layers "B.Cu" "B.Mask" "B.Paste")
			(net "M_F_DQS_DP<5>")
		)
		(pad "257" smd rect
			(at -4.59994 100.300028 270)
			(size 1.8034 0.508)
			(layers "B.Cu" "B.Mask" "B.Paste")
			(net "GND")
		)
		(pad "258" smd rect
			(at -4.59994 101.149912 270)
			(size 1.8034 0.508)
			(layers "B.Cu" "B.Mask" "B.Paste")
			(net "M_F_DQ<47>")
		)
		(pad "259" smd rect
			(at -4.59994 102.00005 270)
			(size 1.8034 0.508)
			(layers "B.Cu" "B.Mask" "B.Paste")
			(net "GND")
		)
		(pad "260" smd rect
			(at -4.59994 102.849934 270)
			(size 1.8034 0.508)
			(layers "B.Cu" "B.Mask" "B.Paste")
			(net "M_F_DQ<43>")
		)
		(pad "261" smd rect
			(at -4.59994 103.700072 270)
			(size 1.8034 0.508)
			(layers "B.Cu" "B.Mask" "B.Paste")
			(net "GND")
		)
		(pad "262" smd rect
			(at -4.59994 104.549956 270)
			(size 1.8034 0.508)
			(layers "B.Cu" "B.Mask" "B.Paste")
			(net "M_F_DQ<53>")
		)
		(pad "263" smd rect
			(at -4.59994 105.400094 270)
			(size 1.8034 0.508)
			(layers "B.Cu" "B.Mask" "B.Paste")
			(net "GND")
		)
		(pad "264" smd rect
			(at -4.59994 106.249978 270)
			(size 1.8034 0.508)
			(layers "B.Cu" "B.Mask" "B.Paste")
			(net "M_F_DQ<49>")
		)
		(pad "265" smd rect
			(at -4.59994 107.100116 270)
			(size 1.8034 0.508)
			(layers "B.Cu" "B.Mask" "B.Paste")
			(net "GND")
		)
		(pad "266" smd rect
			(at -4.59994 107.95 270)
			(size 1.8034 0.508)
			(layers "B.Cu" "B.Mask" "B.Paste")
			(net "M_F_DQS_DN<6>")
		)
		(pad "267" smd rect
			(at -4.59994 108.799884 270)
			(size 1.8034 0.508)
			(layers "B.Cu" "B.Mask" "B.Paste")
			(net "M_F_DQS_DP<6>")
		)
		(pad "268" smd rect
			(at -4.59994 109.650022 270)
			(size 1.8034 0.508)
			(layers "B.Cu" "B.Mask" "B.Paste")
			(net "GND")
		)
		(pad "269" smd rect
			(at -4.59994 110.499906 270)
			(size 1.8034 0.508)
			(layers "B.Cu" "B.Mask" "B.Paste")
			(net "M_F_DQ<55>")
		)
		(pad "270" smd rect
			(at -4.59994 111.350044 270)
			(size 1.8034 0.508)
			(layers "B.Cu" "B.Mask" "B.Paste")
			(net "GND")
		)
		(pad "271" smd rect
			(at -4.59994 112.199928 270)
			(size 1.8034 0.508)
			(layers "B.Cu" "B.Mask" "B.Paste")
			(net "M_F_DQ<51>")
		)
		(pad "272" smd rect
			(at -4.59994 113.050066 270)
			(size 1.8034 0.508)
			(layers "B.Cu" "B.Mask" "B.Paste")
			(net "GND")
		)
		(pad "273" smd rect
			(at -4.59994 113.89995 270)
			(size 1.8034 0.508)
			(layers "B.Cu" "B.Mask" "B.Paste")
			(net "M_F_DQ<61>")
		)
		(pad "274" smd rect
			(at -4.59994 114.750088 270)
			(size 1.8034 0.508)
			(layers "B.Cu" "B.Mask" "B.Paste")
			(net "GND")
		)
		(pad "275" smd rect
			(at -4.59994 115.599972 270)
			(size 1.8034 0.508)
			(layers "B.Cu" "B.Mask" "B.Paste")
			(net "M_F_DQ<57>")
		)
		(pad "276" smd rect
			(at -4.59994 116.45011 270)
			(size 1.8034 0.508)
			(layers "B.Cu" "B.Mask" "B.Paste")
			(net "GND")
		)
		(pad "277" smd rect
			(at -4.59994 117.299994 270)
			(size 1.8034 0.508)
			(layers "B.Cu" "B.Mask" "B.Paste")
			(net "M_F_DQS_DN<7>")
		)
		(pad "278" smd rect
			(at -4.59994 118.149878 270)
			(size 1.8034 0.508)
			(layers "B.Cu" "B.Mask" "B.Paste")
			(net "M_F_DQS_DP<7>")
		)
		(pad "279" smd rect
			(at -4.59994 119.000016 270)
			(size 1.8034 0.508)
			(layers "B.Cu" "B.Mask" "B.Paste")
			(net "GND")
		)
		(pad "280" smd rect
			(at -4.59994 119.8499 270)
			(size 1.8034 0.508)
			(layers "B.Cu" "B.Mask" "B.Paste")
			(net "M_F_DQ<63>")
		)
		(pad "281" smd rect
			(at -4.59994 120.700038 270)
			(size 1.8034 0.508)
			(layers "B.Cu" "B.Mask" "B.Paste")
			(net "GND")
		)
		(pad "282" smd rect
			(at -4.59994 121.549922 270)
			(size 1.8034 0.508)
			(layers "B.Cu" "B.Mask" "B.Paste")
			(net "M_F_DQ<59>")
		)
		(pad "283" smd rect
			(at -4.59994 122.40006 270)
			(size 1.8034 0.508)
			(layers "B.Cu" "B.Mask" "B.Paste")
			(net "GND")
		)
		(pad "284" smd rect
			(at -4.59994 123.249944 270)
			(size 1.8034 0.508)
			(layers "B.Cu" "B.Mask" "B.Paste")
			(net "PVPP_DEF")
		)
		(pad "285" smd rect
			(at -4.59994 124.100082 270)
			(size 1.8034 0.508)
			(layers "B.Cu" "B.Mask" "B.Paste")
			(net "SMB_DDR_DEF_VPP_SDA")
		)
		(pad "286" smd rect
			(at -4.59994 124.949966 270)
			(size 1.8034 0.508)
			(layers "B.Cu" "B.Mask" "B.Paste")
			(net "PVPP_DEF")
		)
		(pad "287" smd rect
			(at -4.59994 125.800104 270)
			(size 1.8034 0.508)
			(layers "B.Cu" "B.Mask" "B.Paste")
			(net "PVPP_DEF")
		)
		(pad "288" smd rect
			(at -4.59994 126.649988 270)
			(size 1.8034 0.508)
			(layers "B.Cu" "B.Mask" "B.Paste")
			(net "PVPP_DEF")
		)
	)
)
